# T6G (Grand Teton) — schematic netlist excerpt (pin names and nets, part order shuffled) for the footprints in the layout excerpt that follows; sources: Cadence DE-HDL packaged netlist, KiCad conversion of 04192023_DAF0TMB3IC0_F0TG_MB_C_brd_V02_OCP.brd

C111  Q_CAP  22UF 4V 20% X6S  pkg C0402  page 334 : A = P1V8_CPU1_RT1_1A ; B = GND
PC2209  Q_CAP  1UF 25V 10% X6S  pkg C0402  page 146 : A = P12V_E1S_VCC_0 ; B = GND

(kicad_pcb
	(version 20260206)
	(generator "pcbnew")
	(generator_version "10.0")
	(general
		(thickness 1.6)
		(legacy_teardrops no)
	)
	(paper "A4")
	(title_block
		(title "04192023_DAF0TMB3IC0_F0TG_MB_C_brd_V02_OCP.brd")
		(comment 1 "Grand Teton / footprints 586-587 of 8354")
	)
	(layers
		(0 "F.Cu" signal "TOP")
		(4 "In1.Cu" signal "GND")
		(6 "In2.Cu" signal "IN1")
		(8 "In3.Cu" signal "GND1")
		(10 "In4.Cu" signal "IN2")
		(12 "In5.Cu" signal "GND2")
		(14 "In6.Cu" signal "IN3")
		(16 "In7.Cu" signal "GND3")
		(18 "In8.Cu" signal "VCC")
		(20 "In9.Cu" signal "VCC1")
		(22 "In10.Cu" signal "GND4")
		(24 "In11.Cu" signal "IN4")
		(26 "In12.Cu" signal "GND5")
		(28 "In13.Cu" signal "IN5")
		(30 "In14.Cu" signal "GND6")
		(32 "In15.Cu" signal "IN6")
		(34 "In16.Cu" signal "GND7")
		(2 "B.Cu" signal "BOTTOM")
		(9 "F.Adhes" user "F.Adhesive")
		(11 "B.Adhes" user "B.Adhesive")
		(13 "F.Paste" user "Package Geometry/Pastemask Top")
		(15 "B.Paste" user "Package Geometry/Pastemask Bottom")
		(5 "F.SilkS" user "Ref Des/Silkscreen Top")
		(7 "B.SilkS" user "Ref Des/Silkscreen Bottom")
		(1 "F.Mask" user "Board Geometry/Soldermask Top")
		(3 "B.Mask" user "Board Geometry/Soldermask Bottom")
		(17 "Dwgs.User" user "User.Drawings")
		(19 "Cmts.User" user "User.Comments")
		(21 "Eco1.User" user "User.Eco1")
		(23 "Eco2.User" user "User.Eco2")
		(25 "Edge.Cuts" user "Board Geometry/Outline")
		(27 "Margin" user)
		(31 "F.CrtYd" user "Package Geometry/Place Bound Top")
		(29 "B.CrtYd" user "Package Geometry/Place Bound Bottom")
		(35 "F.Fab" user "Ref Des/Assembly Top")
		(33 "B.Fab" user "Ref Des/Assembly Bottom")
	)
	(footprint ""
		(layer "F.Cu")
		(at 102.021386 -386.44068 90)
		(property "Reference" "C111"
			(at 0 0 90)
			(layer "F.SilkS")
			(hide yes)
			(effects
				(font
					(size 1.27 1.27)
				)
			)
		)
		(property "Value" ""
			(at 0 0 90)
			(layer "F.Fab")
			(effects
				(font
					(size 1.27 1.27)
				)
			)
		)
		(duplicate_pad_numbers_are_jumpers no)
		(fp_line
			(start 0.7874 -0.4064)
			(end 0.7874 0.4064)
			(stroke
				(width 0.1524)
				(type default)
			)
			(layer "F.SilkS")
		)
		(fp_line
			(start -0.7874 -0.4064)
			(end 0.7874 -0.4064)
			(stroke
				(width 0.1524)
				(type default)
			)
			(layer "F.SilkS")
		)
		(fp_line
			(start 0.7874 0.4064)
			(end -0.7874 0.4064)
			(stroke
				(width 0.1524)
				(type default)
			)
			(layer "F.SilkS")
		)
		(fp_line
			(start -0.7874 0.4064)
			(end -0.7874 -0.4064)
			(stroke
				(width 0.1524)
				(type default)
			)
			(layer "F.SilkS")
		)
		(fp_line
			(start -0.12065 -0.305054)
			(end -0.12065 -0.2794)
			(stroke
				(width 0.1)
				(type default)
			)
			(layer "F.Fab")
		)
		(fp_line
			(start -0.67945 -0.305054)
			(end -0.12065 -0.305054)
			(stroke
				(width 0.1)
				(type default)
			)
			(layer "F.Fab")
		)
		(fp_line
			(start 0.67945 -0.3048)
			(end 0.67945 0.3048)
			(stroke
				(width 0.1)
				(type default)
			)
			(layer "F.Fab")
		)
		(fp_line
			(start 0.12065 -0.3048)
			(end 0.67945 -0.3048)
			(stroke
				(width 0.1)
				(type default)
			)
			(layer "F.Fab")
		)
		(fp_line
			(start 0.12065 -0.2794)
			(end 0.12065 -0.3048)
			(stroke
				(width 0.1)
				(type default)
			)
			(layer "F.Fab")
		)
		(fp_line
			(start -0.12065 -0.2794)
			(end 0.12065 -0.2794)
			(stroke
				(width 0.1)
				(type default)
			)
			(layer "F.Fab")
		)
		(fp_line
			(start 0.120396 0.2794)
			(end -0.12065 0.2794)
			(stroke
				(width 0.1)
				(type default)
			)
			(layer "F.Fab")
		)
		(fp_line
			(start -0.12065 0.2794)
			(end -0.12065 0.3048)
			(stroke
				(width 0.1)
				(type default)
			)
			(layer "F.Fab")
		)
		(fp_line
			(start 0.67945 0.3048)
			(end 0.120396 0.3048)
			(stroke
				(width 0.1)
				(type default)
			)
			(layer "F.Fab")
		)
		(fp_line
			(start 0.120396 0.3048)
			(end 0.120396 0.2794)
			(stroke
				(width 0.1)
				(type default)
			)
			(layer "F.Fab")
		)
		(fp_line
			(start -0.12065 0.3048)
			(end -0.67945 0.3048)
			(stroke
				(width 0.1)
				(type default)
			)
			(layer "F.Fab")
		)
		(fp_line
			(start -0.67945 0.3048)
			(end -0.67945 -0.305054)
			(stroke
				(width 0.1)
				(type default)
			)
			(layer "F.Fab")
		)
		(pad "1" smd circle
			(at -0.40005 0 90)
			(size 0 0)
			(layers "F.Cu" "F.Mask" "F.Paste")
			(net "P1V8_CPU1_RT1_1A")
		)
		(pad "2" smd circle
			(at 0.40005 0 90)
			(size 0 0)
			(layers "F.Cu" "F.Mask" "F.Paste")
			(net "GND")
		)
	)
	(footprint ""
		(layer "F.Cu")
		(at 255.447546 -43.902122 90)
		(property "Reference" "PC2209"
			(at 0 0 90)
			(layer "F.SilkS")
			(hide yes)
			(effects
				(font
					(size 1.27 1.27)
				)
			)
		)
		(property "Value" ""
			(at 0 0 90)
			(layer "F.Fab")
			(effects
				(font
					(size 1.27 1.27)
				)
			)
		)
		(duplicate_pad_numbers_are_jumpers no)
		(fp_line
			(start 0.7874 -0.4064)
			(end 0.7874 0.4064)
			(stroke
				(width 0.1524)
				(type default)
			)
			(layer "F.SilkS")
		)
		(fp_line
			(start -0.7874 -0.4064)
			(end 0.7874 -0.4064)
			(stroke
				(width 0.1524)
				(type default)
			)
			(layer "F.SilkS")
		)
		(fp_line
			(start 0.7874 0.4064)
			(end -0.7874 0.4064)
			(stroke
				(width 0.1524)
				(type default)
			)
			(layer "F.SilkS")
		)
		(fp_line
			(start -0.7874 0.4064)
			(end -0.7874 -0.4064)
			(stroke
				(width 0.1524)
				(type default)
			)
			(layer "F.SilkS")
		)
		(fp_line
			(start -0.12065 -0.305054)
			(end -0.12065 -0.2794)
			(stroke
				(width 0.1)
				(type default)
			)
			(layer "F.Fab")
		)
		(fp_line
			(start -0.67945 -0.305054)
			(end -0.12065 -0.305054)
			(stroke
				(width 0.1)
				(type default)
			)
			(layer "F.Fab")
		)
		(fp_line
			(start 0.67945 -0.3048)
			(end 0.67945 0.3048)
			(stroke
				(width 0.1)
				(type default)
			)
			(layer "F.Fab")
		)
		(fp_line
			(start 0.12065 -0.3048)
			(end 0.67945 -0.3048)
			(stroke
				(width 0.1)
				(type default)
			)
			(layer "F.Fab")
		)
		(fp_line
			(start 0.12065 -0.2794)
			(end 0.12065 -0.3048)
			(stroke
				(width 0.1)
				(type default)
			)
			(layer "F.Fab")
		)
		(fp_line
			(start -0.12065 -0.2794)
			(end 0.12065 -0.2794)
			(stroke
				(width 0.1)
				(type default)
			)
			(layer "F.Fab")
		)
		(fp_line
			(start 0.120396 0.2794)
			(end -0.12065 0.2794)
			(stroke
				(width 0.1)
				(type default)
			)
			(layer "F.Fab")
		)
		(fp_line
			(start -0.12065 0.2794)
			(end -0.12065 0.3048)
			(stroke
				(width 0.1)
				(type default)
			)
			(layer "F.Fab")
		)
		(fp_line
			(start 0.67945 0.3048)
			(end 0.120396 0.3048)
			(stroke
				(width 0.1)
				(type default)
			)
			(layer "F.Fab")
		)
		(fp_line
			(start 0.120396 0.3048)
			(end 0.120396 0.2794)
			(stroke
				(width 0.1)
				(type default)
			)
			(layer "F.Fab")
		)
		(fp_line
			(start -0.12065 0.3048)
			(end -0.67945 0.3048)
			(stroke
				(width 0.1)
				(type default)
			)
			(layer "F.Fab")
		)
		(fp_line
			(start -0.67945 0.3048)
			(end -0.67945 -0.305054)
			(stroke
				(width 0.1)
				(type default)
			)
			(layer "F.Fab")
		)
		(pad "1" smd circle
			(at -0.40005 0 90)
			(size 0 0)
			(layers "F.Cu" "F.Mask" "F.Paste")
			(net "P12V_E1S_VCC_0")
		)
		(pad "2" smd circle
			(at 0.40005 0 90)
			(size 0 0)
			(layers "F.Cu" "F.Mask" "F.Paste")
			(net "GND")
		)
	)
)
